# T6G (Grand Teton) — schematic netlist excerpt (pin names and nets, part order shuffled) for the footprints in the layout excerpt that follows; sources: Cadence DE-HDL packaged netlist, KiCad conversion of 04192023_DAF0TMB3IC0_F0TG_MB_C_brd_V02_OCP.brd

R149  Q_RES  0 5% CHIP  pkg 0402LF  page 210 : A = PVDDCR_SOC_P1_EN ; B = PVDDCR_SOC_P1_EN_RC
PR6609  Q_RES  0 5% CHIP  pkg 0402LF  page 362 : A = NC_P0V9_RETIMER_CPU0_IMON3 ; B = GND

(kicad_pcb
	(version 20260206)
	(generator "pcbnew")
	(generator_version "10.0")
	(general
		(thickness 1.6)
		(legacy_teardrops no)
	)
	(paper "A4")
	(title_block
		(title "04192023_DAF0TMB3IC0_F0TG_MB_C_brd_V02_OCP.brd")
		(comment 1 "Grand Teton / footprints 4656-4657 of 8354")
	)
	(layers
		(0 "F.Cu" signal "TOP")
		(4 "In1.Cu" signal "GND")
		(6 "In2.Cu" signal "IN1")
		(8 "In3.Cu" signal "GND1")
		(10 "In4.Cu" signal "IN2")
		(12 "In5.Cu" signal "GND2")
		(14 "In6.Cu" signal "IN3")
		(16 "In7.Cu" signal "GND3")
		(18 "In8.Cu" signal "VCC")
		(20 "In9.Cu" signal "VCC1")
		(22 "In10.Cu" signal "GND4")
		(24 "In11.Cu" signal "IN4")
		(26 "In12.Cu" signal "GND5")
		(28 "In13.Cu" signal "IN5")
		(30 "In14.Cu" signal "GND6")
		(32 "In15.Cu" signal "IN6")
		(34 "In16.Cu" signal "GND7")
		(2 "B.Cu" signal "BOTTOM")
		(9 "F.Adhes" user "F.Adhesive")
		(11 "B.Adhes" user "B.Adhesive")
		(13 "F.Paste" user "Package Geometry/Pastemask Top")
		(15 "B.Paste" user "Package Geometry/Pastemask Bottom")
		(5 "F.SilkS" user "Ref Des/Silkscreen Top")
		(7 "B.SilkS" user "Ref Des/Silkscreen Bottom")
		(1 "F.Mask" user "Board Geometry/Soldermask Top")
		(3 "B.Mask" user "Board Geometry/Soldermask Bottom")
		(17 "Dwgs.User" user "User.Drawings")
		(19 "Cmts.User" user "User.Comments")
		(21 "Eco1.User" user "User.Eco1")
		(23 "Eco2.User" user "User.Eco2")
		(25 "Edge.Cuts" user "Board Geometry/Outline")
		(27 "Margin" user)
		(31 "F.CrtYd" user "Package Geometry/Place Bound Top")
		(29 "B.CrtYd" user "Package Geometry/Place Bound Bottom")
		(35 "F.Fab" user "Ref Des/Assembly Top")
		(33 "B.Fab" user "Ref Des/Assembly Bottom")
	)
	(footprint ""
		(layer "F.Cu")
		(at 443.982602 -418.17671 -90)
		(property "Reference" "PR6609"
			(at 0 0 270)
			(layer "F.SilkS")
			(hide yes)
			(effects
				(font
					(size 1.27 1.27)
				)
			)
		)
		(property "Value" ""
			(at 0 0 270)
			(layer "F.Fab")
			(effects
				(font
					(size 1.27 1.27)
				)
			)
		)
		(duplicate_pad_numbers_are_jumpers no)
		(fp_line
			(start -0.7874 0.4064)
			(end -0.7874 -0.4064)
			(stroke
				(width 0.1524)
				(type default)
			)
			(layer "F.SilkS")
		)
		(fp_line
			(start 0.7874 0.4064)
			(end -0.7874 0.4064)
			(stroke
				(width 0.1524)
				(type default)
			)
			(layer "F.SilkS")
		)
		(fp_line
			(start -0.7874 -0.4064)
			(end 0.7874 -0.4064)
			(stroke
				(width 0.1524)
				(type default)
			)
			(layer "F.SilkS")
		)
		(fp_line
			(start 0.7874 -0.4064)
			(end 0.7874 0.4064)
			(stroke
				(width 0.1524)
				(type default)
			)
			(layer "F.SilkS")
		)
		(fp_line
			(start -0.67945 0.3048)
			(end -0.67945 -0.305054)
			(stroke
				(width 0.1)
				(type default)
			)
			(layer "F.Fab")
		)
		(fp_line
			(start -0.12065 0.3048)
			(end -0.67945 0.3048)
			(stroke
				(width 0.1)
				(type default)
			)
			(layer "F.Fab")
		)
		(fp_line
			(start 0.120396 0.3048)
			(end 0.120396 0.2794)
			(stroke
				(width 0.1)
				(type default)
			)
			(layer "F.Fab")
		)
		(fp_line
			(start 0.67945 0.3048)
			(end 0.120396 0.3048)
			(stroke
				(width 0.1)
				(type default)
			)
			(layer "F.Fab")
		)
		(fp_line
			(start -0.12065 0.2794)
			(end -0.12065 0.3048)
			(stroke
				(width 0.1)
				(type default)
			)
			(layer "F.Fab")
		)
		(fp_line
			(start 0.120396 0.2794)
			(end -0.12065 0.2794)
			(stroke
				(width 0.1)
				(type default)
			)
			(layer "F.Fab")
		)
		(fp_line
			(start -0.12065 -0.2794)
			(end 0.12065 -0.2794)
			(stroke
				(width 0.1)
				(type default)
			)
			(layer "F.Fab")
		)
		(fp_line
			(start 0.12065 -0.2794)
			(end 0.12065 -0.3048)
			(stroke
				(width 0.1)
				(type default)
			)
			(layer "F.Fab")
		)
		(fp_line
			(start 0.12065 -0.3048)
			(end 0.67945 -0.3048)
			(stroke
				(width 0.1)
				(type default)
			)
			(layer "F.Fab")
		)
		(fp_line
			(start 0.67945 -0.3048)
			(end 0.67945 0.3048)
			(stroke
				(width 0.1)
				(type default)
			)
			(layer "F.Fab")
		)
		(fp_line
			(start -0.67945 -0.305054)
			(end -0.12065 -0.305054)
			(stroke
				(width 0.1)
				(type default)
			)
			(layer "F.Fab")
		)
		(fp_line
			(start -0.12065 -0.305054)
			(end -0.12065 -0.2794)
			(stroke
				(width 0.1)
				(type default)
			)
			(layer "F.Fab")
		)
		(pad "1" smd circle
			(at -0.40005 0 270)
			(size 0 0)
			(layers "F.Cu" "F.Mask" "F.Paste")
			(net "NC_P0V9_RETIMER_CPU0_IMON3")
		)
		(pad "2" smd circle
			(at 0.40005 0 270)
			(size 0 0)
			(layers "F.Cu" "F.Mask" "F.Paste")
			(net "GND")
		)
	)
	(footprint ""
		(layer "F.Cu")
		(at 94.478348 -136.059418 90)
		(property "Reference" "R149"
			(at 0 0 90)
			(layer "F.SilkS")
			(hide yes)
			(effects
				(font
					(size 1.27 1.27)
				)
			)
		)
		(property "Value" ""
			(at 0 0 90)
			(layer "F.Fab")
			(effects
				(font
					(size 1.27 1.27)
				)
			)
		)
		(duplicate_pad_numbers_are_jumpers no)
		(fp_line
			(start 0.7874 -0.4064)
			(end 0.7874 0.4064)
			(stroke
				(width 0.1524)
				(type default)
			)
			(layer "F.SilkS")
		)
		(fp_line
			(start -0.7874 -0.4064)
			(end 0.7874 -0.4064)
			(stroke
				(width 0.1524)
				(type default)
			)
			(layer "F.SilkS")
		)
		(fp_line
			(start 0.7874 0.4064)
			(end -0.7874 0.4064)
			(stroke
				(width 0.1524)
				(type default)
			)
			(layer "F.SilkS")
		)
		(fp_line
			(start -0.7874 0.4064)
			(end -0.7874 -0.4064)
			(stroke
				(width 0.1524)
				(type default)
			)
			(layer "F.SilkS")
		)
		(fp_line
			(start -0.12065 -0.305054)
			(end -0.12065 -0.2794)
			(stroke
				(width 0.1)
				(type default)
			)
			(layer "F.Fab")
		)
		(fp_line
			(start -0.67945 -0.305054)
			(end -0.12065 -0.305054)
			(stroke
				(width 0.1)
				(type default)
			)
			(layer "F.Fab")
		)
		(fp_line
			(start 0.67945 -0.3048)
			(end 0.67945 0.3048)
			(stroke
				(width 0.1)
				(type default)
			)
			(layer "F.Fab")
		)
		(fp_line
			(start 0.12065 -0.3048)
			(end 0.67945 -0.3048)
			(stroke
				(width 0.1)
				(type default)
			)
			(layer "F.Fab")
		)
		(fp_line
			(start 0.12065 -0.2794)
			(end 0.12065 -0.3048)
			(stroke
				(width 0.1)
				(type default)
			)
			(layer "F.Fab")
		)
		(fp_line
			(start -0.12065 -0.2794)
			(end 0.12065 -0.2794)
			(stroke
				(width 0.1)
				(type default)
			)
			(layer "F.Fab")
		)
		(fp_line
			(start 0.120396 0.2794)
			(end -0.12065 0.2794)
			(stroke
				(width 0.1)
				(type default)
			)
			(layer "F.Fab")
		)
		(fp_line
			(start -0.12065 0.2794)
			(end -0.12065 0.3048)
			(stroke
				(width 0.1)
				(type default)
			)
			(layer "F.Fab")
		)
		(fp_line
			(start 0.67945 0.3048)
			(end 0.120396 0.3048)
			(stroke
				(width 0.1)
				(type default)
			)
			(layer "F.Fab")
		)
		(fp_line
			(start 0.120396 0.3048)
			(end 0.120396 0.2794)
			(stroke
				(width 0.1)
				(type default)
			)
			(layer "F.Fab")
		)
		(fp_line
			(start -0.12065 0.3048)
			(end -0.67945 0.3048)
			(stroke
				(width 0.1)
				(type default)
			)
			(layer "F.Fab")
		)
		(fp_line
			(start -0.67945 0.3048)
			(end -0.67945 -0.305054)
			(stroke
				(width 0.1)
				(type default)
			)
			(layer "F.Fab")
		)
		(pad "1" smd circle
			(at -0.40005 0 90)
			(size 0 0)
			(layers "F.Cu" "F.Mask" "F.Paste")
			(net "PVDDCR_SOC_P1_EN")
		)
		(pad "2" smd circle
			(at 0.40005 0 90)
			(size 0 0)
			(layers "F.Cu" "F.Mask" "F.Paste")
			(net "PVDDCR_SOC_P1_EN_RC")
		)
	)
)
